(kicad_pcb
	(version 20241229)
	(generator "pcbnew")
	(generator_version "9.0")
	(general
		(thickness 1.294)
		(legacy_teardrops no)
	)
	(paper "A3")
	(title_block
		(title "Kintex 410T devboard")
		(date "2024-04-03")
		(rev "1.1.2")
		(comment 9 "footprints 102-105 of 975")
	)
	(layers
		(0 "F.Cu" mixed)
		(4 "In1.Cu" power)
		(6 "In2.Cu" power)
		(8 "In3.Cu" mixed)
		(10 "In4.Cu" power)
		(12 "In5.Cu" mixed)
		(14 "In6.Cu" power)
		(16 "In7.Cu" mixed)
		(18 "In8.Cu" power)
		(2 "B.Cu" mixed)
		(9 "F.Adhes" user "F.Adhesive")
		(11 "B.Adhes" user "B.Adhesive")
		(13 "F.Paste" user)
		(15 "B.Paste" user)
		(5 "F.SilkS" user "F.Silkscreen")
		(7 "B.SilkS" user "B.Silkscreen")
		(1 "F.Mask" user)
		(3 "B.Mask" user)
		(17 "Dwgs.User" user "User.Drawings")
		(19 "Cmts.User" user "User.Comments")
		(21 "Eco1.User" user "User.Eco1")
		(23 "Eco2.User" user "User.Eco2")
		(25 "Edge.Cuts" user)
		(27 "Margin" user)
		(31 "F.CrtYd" user "F.Courtyard")
		(29 "B.CrtYd" user "B.Courtyard")
		(35 "F.Fab" user)
		(33 "B.Fab" user)
	)
	(footprint "antmicro-footprints:LGA-33_7x7mm_P0.65mm"
		(layer "F.Cu")
		(at 159.1625 170.825 180)
		(property "Reference" "U31"
			(at 5.2875 3.825 180)
			(layer "F.SilkS")
			(effects
				(font
					(size 0.7 0.7)
					(thickness 0.15)
				)
				(justify left bottom)
			)
		)
		(property "Value" "MPM54304GMN"
			(at -3.5 0.3 180)
			(layer "F.Fab")
			(effects
				(font
					(size 0.7 0.7)
					(thickness 0.15)
				)
				(justify left bottom)
			)
		)
		(property "Description" "DC-DC Switching Synchronous Step-Down Regulator, Multi Output, 4-16V in, 1V/3.3V, 4.2/3A out, LGA33"
			(at 0 0 180)
			(layer "F.Fab")
			(hide yes)
			(effects
				(font
					(size 1.27 1.27)
					(thickness 0.15)
				)
			)
		)
		(property "Author" "Antmicro"
			(at 318.325 341.65 0)
			(layer "F.Fab")
			(hide yes)
			(effects
				(font
					(size 1 1)
					(thickness 0.15)
				)
			)
		)
		(property "License" "Apache-2.0"
			(at 318.325 341.65 0)
			(layer "F.Fab")
			(hide yes)
			(effects
				(font
					(size 1 1)
					(thickness 0.15)
				)
			)
		)
		(property "MPN" "MPM54304GMN-0000"
			(at 318.325 341.65 0)
			(layer "F.Fab")
			(hide yes)
			(effects
				(font
					(size 1 1)
					(thickness 0.15)
				)
			)
		)
		(property "Manufacturer" "Monolithic Power Systems"
			(at 318.325 341.65 0)
			(layer "F.Fab")
			(hide yes)
			(effects
				(font
					(size 1 1)
					(thickness 0.15)
				)
			)
		)
		(sheetname "DC-DC Converters")
		(sheetfile "dc-dc.kicad_sch")
		(solder_paste_margin_ratio -0.1)
		(attr smd)
		(fp_line
			(start 3.648 3.648)
			(end 3.648 2.922)
			(stroke
				(width 0.15)
				(type solid)
			)
			(layer "F.SilkS")
		)
		(fp_line
			(start 3.648 -3.65)
			(end 3.648 -2.926)
			(stroke
				(width 0.15)
				(type solid)
			)
			(layer "F.SilkS")
		)
		(fp_line
			(start 2.922 3.648)
			(end 3.648 3.648)
			(stroke
				(width 0.15)
				(type solid)
			)
			(layer "F.SilkS")
		)
		(fp_line
			(start 2.922 -3.65)
			(end 3.648 -3.65)
			(stroke
				(width 0.15)
				(type solid)
			)
			(layer "F.SilkS")
		)
		(fp_line
			(start -2.926 3.648)
			(end -3.65 3.648)
			(stroke
				(width 0.15)
				(type solid)
			)
			(layer "F.SilkS")
		)
		(fp_line
			(start -3.65 3.648)
			(end -3.65 2.922)
			(stroke
				(width 0.15)
				(type solid)
			)
			(layer "F.SilkS")
		)
		(fp_line
			(start -3.665 -2.928)
			(end -3.665 -3.653)
			(stroke
				(width 0.15)
				(type solid)
			)
			(layer "F.SilkS")
		)
		(fp_line
			(start -3.665 -3.653)
			(end -2.94 -3.653)
			(stroke
				(width 0.15)
				(type solid)
			)
			(layer "F.SilkS")
		)
		(fp_circle
			(center -3.8 -1.925)
			(end -3.75 -1.925)
			(stroke
				(width 0.15)
				(type solid)
			)
			(fill yes)
			(layer "F.SilkS")
		)
		(fp_rect
			(start -4 -4)
			(end 3.999 3.999)
			(stroke
				(width 0.05)
				(type solid)
			)
			(fill no)
			(layer "F.CrtYd")
		)
		(fp_line
			(start 3.499 3.499)
			(end 3.499 -3.5)
			(stroke
				(width 0.15)
				(type solid)
			)
			(layer "F.Fab")
		)
		(fp_line
			(start 3.499 -3.5)
			(end -3.5 -3.5)
			(stroke
				(width 0.15)
				(type solid)
			)
			(layer "F.Fab")
		)
		(fp_line
			(start -3.101 -3.5)
			(end -3.5 -3.101)
			(stroke
				(width 0.15)
				(type solid)
			)
			(layer "F.Fab")
		)
		(fp_line
			(start -3.5 3.499)
			(end 3.499 3.499)
			(stroke
				(width 0.15)
				(type solid)
			)
			(layer "F.Fab")
		)
		(fp_line
			(start -3.5 -3.5)
			(end -3.5 3.499)
			(stroke
				(width 0.15)
				(type solid)
			)
			(layer "F.Fab")
		)
		(pad "1" smd rect
			(at -3.138 -1.625 270)
			(size 0.3 1.125)
			(layers "F.Cu" "F.Mask" "F.Paste")
			(net 737 "/DC-DC Converters/1V2_local")
			(pinfunction "VOUT3")
			(pintype "power_out")
		)
		(pad "2" smd rect
			(at -3.138 -0.975 270)
			(size 0.3 1.125)
			(layers "F.Cu" "F.Mask" "F.Paste")
			(net 1 "GND")
			(pinfunction "GND")
			(pintype "passive")
		)
		(pad "3" smd rect
			(at -3.138 -0.328 270)
			(size 0.3 1.125)
			(layers "F.Cu" "F.Mask" "F.Paste")
			(net 1336 "/I2C.SDA")
			(pinfunction "SDA")
			(pintype "bidirectional")
		)
		(pad "4" smd rect
			(at -3.138 0.325 270)
			(size 0.3 1.125)
			(layers "F.Cu" "F.Mask" "F.Paste")
			(net 1394 "/I2C.QDCDC1_SCL")
			(pinfunction "SCL")
			(pintype "input")
		)
		(pad "5" smd rect
			(at -3.138 0.972 270)
			(size 0.3 1.125)
			(layers "F.Cu" "F.Mask" "F.Paste")
			(net 1 "GND")
			(pinfunction "GND")
			(pintype "passive")
		)
		(pad "6" smd rect
			(at -3.138 1.624 270)
			(size 0.3 1.125)
			(layers "F.Cu" "F.Mask" "F.Paste")
			(net 960 "/DC-DC Converters/FB2")
			(pinfunction "FB2")
			(pintype "input")
		)
		(pad "7" smd rect
			(at -2.926 3.136)
			(size 0.3 1.125)
			(layers "F.Cu" "F.Mask" "F.Paste")
			(net 1 "GND")
			(pinfunction "GND")
			(pintype "passive")
		)
		(pad "8" smd rect
			(at -2.275 3.136)
			(size 0.3 1.125)
			(layers "F.Cu" "F.Mask" "F.Paste")
			(net 734 "/DC-DC Converters/1V8_local")
			(pinfunction "VOUT2")
			(pintype "power_out")
		)
		(pad "9" smd rect
			(at -1.625 3.136 180)
			(size 0.3 1.125)
			(layers "F.Cu" "F.Mask" "F.Paste")
			(net 734 "/DC-DC Converters/1V8_local")
			(pinfunction "VOUT2")
			(pintype "passive")
		)
		(pad "10" smd rect
			(at -0.975 3.136 180)
			(size 0.3 1.125)
			(layers "F.Cu" "F.Mask" "F.Paste")
			(net 1 "GND")
			(pinfunction "GND")
			(pintype "passive")
		)
		(pad "11" smd rect
			(at -0.328 3.136 180)
			(size 0.3 1.125)
			(layers "F.Cu" "F.Mask" "F.Paste")
			(net 1405 "unconnected-(U31-SW2-Pad11)")
			(pinfunction "SW2")
			(pintype "power_out+no_connect")
		)
		(pad "12" smd rect
			(at 0.325 3.136 180)
			(size 0.3 1.125)
			(layers "F.Cu" "F.Mask" "F.Paste")
			(net 1406 "unconnected-(U31-SW1-Pad12)")
			(pinfunction "SW1")
			(pintype "power_out+no_connect")
		)
		(pad "13" smd rect
			(at 0.972 3.136 180)
			(size 0.3 1.125)
			(layers "F.Cu" "F.Mask" "F.Paste")
			(net 1 "GND")
			(pinfunction "GND")
			(pintype "passive")
		)
		(pad "14" smd rect
			(at 1.624 3.136 180)
			(size 0.3 1.125)
			(layers "F.Cu" "F.Mask" "F.Paste")
			(net 733 "/DC-DC Converters/MGTAVCC_local")
			(pinfunction "VOUT1")
			(pintype "power_out")
		)
		(pad "15" smd rect
			(at 2.273 3.136 180)
			(size 0.3 1.125)
			(layers "F.Cu" "F.Mask" "F.Paste")
			(net 733 "/DC-DC Converters/MGTAVCC_local")
			(pinfunction "VOUT1")
			(pintype "passive")
		)
		(pad "16" smd rect
			(at 2.922 3.136 180)
			(size 0.3 1.125)
			(layers "F.Cu" "F.Mask" "F.Paste")
			(net 1 "GND")
			(pinfunction "GND")
			(pintype "passive")
		)
		(pad "17" smd rect
			(at 3.136 1.624 270)
			(size 0.3 1.125)
			(layers "F.Cu" "F.Mask" "F.Paste")
			(net 1 "GND")
			(pinfunction "SGND1")
			(pintype "power_out")
		)
		(pad "18" smd rect
			(at 3.136 0.972 270)
			(size 0.3 1.125)
			(layers "F.Cu" "F.Mask" "F.Paste")
			(net 959 "/DC-DC Converters/FB1")
			(pinfunction "FB1")
			(pintype "input")
		)
		(pad "19" smd rect
			(at 3.136 0.325 270)
			(size 0.3 1.125)
			(layers "F.Cu" "F.Mask" "F.Paste")
			(net 967 "/DC-DC Converters/EN2")
			(pinfunction "EN/SYNCI")
			(pintype "input")
		)
		(pad "20" smd rect
			(at 3.136 -0.328 270)
			(size 0.3 1.125)
			(layers "F.Cu" "F.Mask" "F.Paste")
			(net 1 "GND")
			(pinfunction "GND")
			(pintype "passive")
		)
		(pad "21" smd rect
			(at 3.136 -0.975 270)
			(size 0.3 1.125)
			(layers "F.Cu" "F.Mask" "F.Paste")
			(net 1 "GND")
			(pinfunction "GND")
			(pintype "passive")
		)
		(pad "22" smd rect
			(at 3.136 -1.625 270)
			(size 0.3 1.125)
			(layers "F.Cu" "F.Mask" "F.Paste")
			(net 738 "/DC-DC Converters/1V7_local")
			(pinfunction "VOUT4")
			(pintype "power_out")
		)
		(pad "23" smd rect
			(at 2.922 -3.138)
			(size 0.3 1.125)
			(layers "F.Cu" "F.Mask" "F.Paste")
			(net 738 "/DC-DC Converters/1V7_local")
			(pinfunction "VOUT4")
			(pintype "passive")
		)
		(pad "24" smd rect
			(at 2.273 -3.138)
			(size 0.3 1.125)
			(layers "F.Cu" "F.Mask" "F.Paste")
			(net 963 "/DC-DC Converters/FB4")
			(pinfunction "FB4")
			(pintype "input")
		)
		(pad "25" smd rect
			(at 1.624 -3.138 180)
			(size 0.3 1.125)
			(layers "F.Cu" "F.Mask" "F.Paste")
			(net 731 "/DC-DC Converters/QDCDC1_VCC")
			(pinfunction "VCC")
			(pintype "input")
		)
		(pad "26" smd rect
			(at 0.972 -3.138 180)
			(size 0.3 1.125)
			(layers "F.Cu" "F.Mask" "F.Paste")
			(net 1413 "/SUP_MCU.PG_1V2")
			(pinfunction "GPIO")
			(pintype "input")
		)
		(pad "27" smd rect
			(at 0.325 -3.138 180)
			(size 0.3 1.125)
			(layers "F.Cu" "F.Mask" "F.Paste")
			(net 1 "GND")
			(pinfunction "GND")
			(pintype "passive")
		)
		(pad "28" smd rect
			(at -0.328 -3.138 180)
			(size 0.3 1.125)
			(layers "F.Cu" "F.Mask" "F.Paste")
			(net 702 "VDC")
			(pinfunction "VIN")
			(pintype "input")
		)
		(pad "29" smd rect
			(at -0.975 -3.138 180)
			(size 0.3 1.125)
			(layers "F.Cu" "F.Mask" "F.Paste")
			(net 702 "VDC")
			(pinfunction "VIN")
			(pintype "passive")
		)
		(pad "30" smd rect
			(at -1.625 -3.138 180)
			(size 0.3 1.125)
			(layers "F.Cu" "F.Mask" "F.Paste")
			(net 1 "GND")
			(pinfunction "SGND2")
			(pintype "power_out")
		)
		(pad "31" smd rect
			(at -2.275 -3.138 180)
			(size 0.3 1.125)
			(layers "F.Cu" "F.Mask" "F.Paste")
			(net 962 "/DC-DC Converters/FB3")
			(pinfunction "FB3")
			(pintype "input")
		)
		(pad "32" smd rect
			(at -2.926 -3.138 180)
			(size 0.3 1.125)
			(layers "F.Cu" "F.Mask" "F.Paste")
			(net 737 "/DC-DC Converters/1V2_local")
			(pinfunction "VOUT3")
			(pintype "passive")
		)
		(pad "33" smd rect
			(at -0.863 -0.863 180)
			(size 1.725 1.725)
			(layers "F.Cu" "F.Mask" "F.Paste")
			(net 1 "GND")
			(pinfunction "GND")
			(pintype "passive")
			(solder_paste_margin -0.1)
		)
		(pad "33" smd rect
			(at -0.863 0.86 180)
			(size 1.725 1.725)
			(layers "F.Cu" "F.Mask" "F.Paste")
			(net 1 "GND")
			(pinfunction "GND")
			(pintype "passive")
			(solder_paste_margin -0.1)
		)
		(pad "33" smd rect
			(at 0.86 -0.863 180)
			(size 1.725 1.725)
			(layers "F.Cu" "F.Mask" "F.Paste")
			(net 1 "GND")
			(pinfunction "GND")
			(pintype "passive")
			(solder_paste_margin -0.1)
		)
		(pad "33" smd rect
			(at 0.86 0.86 180)
			(size 1.725 1.725)
			(layers "F.Cu" "F.Mask" "F.Paste")
			(net 1 "GND")
			(pinfunction "GND")
			(pintype "passive")
			(solder_paste_margin -0.1)
		)
	)
	(footprint "antmicro-footprints:R_0402_1005Metric"
		(layer "F.Cu")
		(at 235.915 120.5 180)
		(descr "Resistor SMD 0402")
		(tags "resistor SMD 0402")
		(property "Reference" "R75"
			(at -0.735 -0.35 180)
			(layer "F.SilkS")
			(effects
				(font
					(size 0.7 0.7)
					(thickness 0.15)
				)
				(justify left bottom)
			)
		)
		(property "Value" "R_0R_0402"
			(at 0 1.4 180)
			(layer "F.Fab")
			(effects
				(font
					(size 0.7 0.7)
					(thickness 0.15)
				)
				(justify left bottom)
			)
		)
		(property "Description" "SMD Chip Resistor, Jumper, 0 ohm, 100 mW, 0402 [1005 Metric], Thick Film, General Purpose"
			(at 0 0 180)
			(layer "F.Fab")
			(hide yes)
			(effects
				(font
					(size 1.27 1.27)
					(thickness 0.15)
				)
			)
		)
		(property "Author" "Antmicro"
			(at 471.83 241 0)
			(layer "F.Fab")
			(hide yes)
			(effects
				(font
					(size 1 1)
					(thickness 0.15)
				)
			)
		)
		(property "Current" "1A"
			(at 471.83 241 0)
			(layer "F.Fab")
			(hide yes)
			(effects
				(font
					(size 1 1)
					(thickness 0.15)
				)
			)
		)
		(property "License" "Apache-2.0"
			(at 471.83 241 0)
			(layer "F.Fab")
			(hide yes)
			(effects
				(font
					(size 1 1)
					(thickness 0.15)
				)
			)
		)
		(property "MPN" "ERJ2GE0R00X"
			(at 471.83 241 0)
			(layer "F.Fab")
			(hide yes)
			(effects
				(font
					(size 1 1)
					(thickness 0.15)
				)
			)
		)
		(property "Manufacturer" "Panasonic"
			(at 471.83 241 0)
			(layer "F.Fab")
			(hide yes)
			(effects
				(font
					(size 1 1)
					(thickness 0.15)
				)
			)
		)
		(property "Tolerance" ""
			(at 471.83 241 0)
			(layer "F.Fab")
			(hide yes)
			(effects
				(font
					(size 1 1)
					(thickness 0.15)
				)
			)
		)
		(property "Val" "0R"
			(at 471.83 241 0)
			(layer "F.Fab")
			(hide yes)
			(effects
				(font
					(size 1 1)
					(thickness 0.15)
				)
			)
		)
		(sheetname "SPI Flash + SD Card")
		(sheetfile "spi-flash.kicad_sch")
		(attr smd)
		(fp_rect
			(start -0.925 -0.47)
			(end 0.925 0.47)
			(stroke
				(width 0.05)
				(type default)
			)
			(fill no)
			(layer "F.CrtYd")
		)
		(fp_rect
			(start -0.5 -0.25)
			(end 0.5 0.25)
			(stroke
				(width 0.15)
				(type solid)
			)
			(fill no)
			(layer "F.Fab")
		)
		(pad "1" smd roundrect
			(at -0.48 0 180)
			(size 0.59 0.64)
			(layers "F.Cu" "F.Mask" "F.Paste")
			(roundrect_rratio 0.25)
			(net 56 "/FPGA Bank 14 & 15/SYSTEM_FLASH.CLK")
			(pintype "passive")
		)
		(pad "2" smd roundrect
			(at 0.48 0 180)
			(size 0.59 0.64)
			(layers "F.Cu" "F.Mask" "F.Paste")
			(roundrect_rratio 0.25)
			(net 895 "/SPI Flash + SD Card/SYSTEM_FLASH_CLK")
			(pintype "passive")
		)
	)
	(footprint "antmicro-footprints:R_0402_1005Metric"
		(layer "F.Cu")
		(at 214.9 165.4 90)
		(descr "Resistor SMD 0402")
		(tags "resistor SMD 0402")
		(property "Reference" "R84"
			(at -0.4 -5.25 90)
			(layer "F.SilkS")
			(effects
				(font
					(size 0.7 0.7)
					(thickness 0.15)
				)
				(justify left bottom)
			)
		)
		(property "Value" "R_0R_0402"
			(at 0 1.4 90)
			(layer "F.Fab")
			(effects
				(font
					(size 0.7 0.7)
					(thickness 0.15)
				)
				(justify left bottom)
			)
		)
		(property "Description" "SMD Chip Resistor, Jumper, 0 ohm, 100 mW, 0402 [1005 Metric], Thick Film, General Purpose"
			(at 0 0 90)
			(layer "F.Fab")
			(hide yes)
			(effects
				(font
					(size 1.27 1.27)
					(thickness 0.15)
				)
			)
		)
		(property "Author" "Antmicro"
			(at 380.3 -49.5 0)
			(layer "F.Fab")
			(hide yes)
			(effects
				(font
					(size 1 1)
					(thickness 0.15)
				)
			)
		)
		(property "Current" "1A"
			(at 380.3 -49.5 0)
			(layer "F.Fab")
			(hide yes)
			(effects
				(font
					(size 1 1)
					(thickness 0.15)
				)
			)
		)
		(property "License" "Apache-2.0"
			(at 380.3 -49.5 0)
			(layer "F.Fab")
			(hide yes)
			(effects
				(font
					(size 1 1)
					(thickness 0.15)
				)
			)
		)
		(property "MPN" "ERJ2GE0R00X"
			(at 380.3 -49.5 0)
			(layer "F.Fab")
			(hide yes)
			(effects
				(font
					(size 1 1)
					(thickness 0.15)
				)
			)
		)
		(property "Manufacturer" "Panasonic"
			(at 380.3 -49.5 0)
			(layer "F.Fab")
			(hide yes)
			(effects
				(font
					(size 1 1)
					(thickness 0.15)
				)
			)
		)
		(property "Tolerance" ""
			(at 380.3 -49.5 0)
			(layer "F.Fab")
			(hide yes)
			(effects
				(font
					(size 1 1)
					(thickness 0.15)
				)
			)
		)
		(property "Val" "0R"
			(at 380.3 -49.5 0)
			(layer "F.Fab")
			(hide yes)
			(effects
				(font
					(size 1 1)
					(thickness 0.15)
				)
			)
		)
		(sheetname "SPI Flash + SD Card")
		(sheetfile "spi-flash.kicad_sch")
		(attr smd)
		(fp_rect
			(start -0.925 -0.47)
			(end 0.925 0.47)
			(stroke
				(width 0.05)
				(type default)
			)
			(fill no)
			(layer "F.CrtYd")
		)
		(fp_rect
			(start -0.5 -0.25)
			(end 0.5 0.25)
			(stroke
				(width 0.15)
				(type solid)
			)
			(fill no)
			(layer "F.Fab")
		)
		(pad "1" smd roundrect
			(at -0.48 0 90)
			(size 0.59 0.64)
			(layers "F.Cu" "F.Mask" "F.Paste")
			(roundrect_rratio 0.25)
			(net 404 "/FPGA Bank 33 & 34/USR_FLASH_0.DQ2")
			(pintype "passive")
		)
		(pad "2" smd roundrect
			(at 0.48 0 90)
			(size 0.59 0.64)
			(layers "F.Cu" "F.Mask" "F.Paste")
			(roundrect_rratio 0.25)
			(net 904 "/SPI Flash + SD Card/USR_FLASH_0_DQ2")
			(pintype "passive")
		)
	)
	(footprint "antmicro-footprints:R_0402_1005Metric"
		(layer "F.Cu")
		(at 235.9 113.6 180)
		(descr "Resistor SMD 0402")
		(tags "resistor SMD 0402")
		(property "Reference" "R100"
			(at -0.8 -0.35 180)
			(layer "F.SilkS")
			(effects
				(font
					(size 0.7 0.7)
					(thickness 0.15)
				)
				(justify left bottom)
			)
		)
		(property "Value" "R_0R_0402"
			(at 0 1.4 180)
			(layer "F.Fab")
			(effects
				(font
					(size 0.7 0.7)
					(thickness 0.15)
				)
				(justify left bottom)
			)
		)
		(property "Description" "SMD Chip Resistor, Jumper, 0 ohm, 100 mW, 0402 [1005 Metric], Thick Film, General Purpose"
			(at 0 0 180)
			(layer "F.Fab")
			(hide yes)
			(effects
				(font
					(size 1.27 1.27)
					(thickness 0.15)
				)
			)
		)
		(property "Author" "Antmicro"
			(at 471.8 227.2 0)
			(layer "F.Fab")
			(hide yes)
			(effects
				(font
					(size 1 1)
					(thickness 0.15)
				)
			)
		)
		(property "Current" "1A"
			(at 471.8 227.2 0)
			(layer "F.Fab")
			(hide yes)
			(effects
				(font
					(size 1 1)
					(thickness 0.15)
				)
			)
		)
		(property "License" "Apache-2.0"
			(at 471.8 227.2 0)
			(layer "F.Fab")
			(hide yes)
			(effects
				(font
					(size 1 1)
					(thickness 0.15)
				)
			)
		)
		(property "MPN" "ERJ2GE0R00X"
			(at 471.8 227.2 0)
			(layer "F.Fab")
			(hide yes)
			(effects
				(font
					(size 1 1)
					(thickness 0.15)
				)
			)
		)
		(property "Manufacturer" "Panasonic"
			(at 471.8 227.2 0)
			(layer "F.Fab")
			(hide yes)
			(effects
				(font
					(size 1 1)
					(thickness 0.15)
				)
			)
		)
		(property "Tolerance" ""
			(at 471.8 227.2 0)
			(layer "F.Fab")
			(hide yes)
			(effects
				(font
					(size 1 1)
					(thickness 0.15)
				)
			)
		)
		(property "Val" "0R"
			(at 471.8 227.2 0)
			(layer "F.Fab")
			(hide yes)
			(effects
				(font
					(size 1 1)
					(thickness 0.15)
				)
			)
		)
		(sheetname "SPI Flash + SD Card")
		(sheetfile "spi-flash.kicad_sch")
		(attr smd)
		(fp_rect
			(start -0.925 -0.47)
			(end 0.925 0.47)
			(stroke
				(width 0.05)
				(type default)
			)
			(fill no)
			(layer "F.CrtYd")
		)
		(fp_rect
			(start -0.5 -0.25)
			(end 0.5 0.25)
			(stroke
				(width 0.15)
				(type solid)
			)
			(fill no)
			(layer "F.Fab")
		)
		(pad "1" smd roundrect
			(at -0.48 0 180)
			(size 0.59 0.64)
			(layers "F.Cu" "F.Mask" "F.Paste")
			(roundrect_rratio 0.25)
			(net 427 "/FPGA Bank 16 & 17/USR_FLASH_1.CLK")
			(pintype "passive")
		)
		(pad "2" smd roundrect
			(at 0.48 0 180)
			(size 0.59 0.64)
			(layers "F.Cu" "F.Mask" "F.Paste")
			(roundrect_rratio 0.25)
			(net 907 "/SPI Flash + SD Card/USR_FLASH_1_CLK")
			(pintype "passive")
		)
	)
)
